# S9S_MB_2U (Grand Teton) — schematic netlist excerpt (pin names and nets, part order shuffled) for the footprints in the layout excerpt that follows; sources: Cadence DE-HDL packaged netlist, KiCad conversion of 03242023_DA0F0TMBIJ0_F0T_Motherboard_J_brd_V01_OCP.brd

R4266  Q_RES  33.2 1% CHIP  pkg 0402LF  page 246 : A = PWRGD_P3V3_AUX_PDB_BUF_R ; B = PWRGD_P3V3_AUX_PDB_BUF
R806  Q_RES  33.2 1% CHIP  pkg 0402LF  page 221 : A = JTAG_PLD_TCK_R ; B = JTAG_BMC_PLD_TCK

(kicad_pcb
	(version 20260206)
	(generator "pcbnew")
	(generator_version "10.0")
	(general
		(thickness 1.6)
		(legacy_teardrops no)
	)
	(paper "A4")
	(title_block
		(title "03242023_DA0F0TMBIJ0_F0T_Motherboard_J_brd_V01_OCP.brd")
		(comment 1 "Grand Teton / footprints 1184-1185 of 6105")
	)
	(layers
		(0 "F.Cu" signal "TOP")
		(4 "In1.Cu" signal "GND")
		(6 "In2.Cu" signal "IN1")
		(8 "In3.Cu" signal "GND1")
		(10 "In4.Cu" signal "IN2")
		(12 "In5.Cu" signal "GND2")
		(14 "In6.Cu" signal "IN3")
		(16 "In7.Cu" signal "GND3")
		(18 "In8.Cu" signal "VCC")
		(20 "In9.Cu" signal "VCC1")
		(22 "In10.Cu" signal "GND4")
		(24 "In11.Cu" signal "IN4")
		(26 "In12.Cu" signal "GND5")
		(28 "In13.Cu" signal "IN5")
		(30 "In14.Cu" signal "GND6")
		(32 "In15.Cu" signal "IN6")
		(34 "In16.Cu" signal "GND7")
		(2 "B.Cu" signal "BOTTOM")
		(9 "F.Adhes" user "F.Adhesive")
		(11 "B.Adhes" user "B.Adhesive")
		(13 "F.Paste" user "Package Geometry/Pastemask Top")
		(15 "B.Paste" user "Package Geometry/Pastemask Bottom")
		(5 "F.SilkS" user "Ref Des/Silkscreen Top")
		(7 "B.SilkS" user "Ref Des/Silkscreen Bottom")
		(1 "F.Mask" user "Board Geometry/Soldermask Top")
		(3 "B.Mask" user "Board Geometry/Soldermask Bottom")
		(17 "Dwgs.User" user "User.Drawings")
		(19 "Cmts.User" user "User.Comments")
		(21 "Eco1.User" user "User.Eco1")
		(23 "Eco2.User" user "User.Eco2")
		(25 "Edge.Cuts" user "Board Geometry/Outline")
		(27 "Margin" user)
		(31 "F.CrtYd" user "Package Geometry/Place Bound Top")
		(29 "B.CrtYd" user "Package Geometry/Place Bound Bottom")
		(35 "F.Fab" user "Ref Des/Assembly Top")
		(33 "B.Fab" user "Ref Des/Assembly Bottom")
	)
	(footprint ""
		(layer "F.Cu")
		(at 307.93309 -427.170342)
		(property "Reference" "R4266"
			(at 0 0 0)
			(layer "F.SilkS")
			(hide yes)
			(effects
				(font
					(size 1.27 1.27)
				)
			)
		)
		(property "Value" ""
			(at 0 0 0)
			(layer "F.Fab")
			(effects
				(font
					(size 1.27 1.27)
				)
			)
		)
		(duplicate_pad_numbers_are_jumpers no)
		(fp_line
			(start -0.7874 -0.4064)
			(end 0.7874 -0.4064)
			(stroke
				(width 0.1524)
				(type default)
			)
			(layer "F.SilkS")
		)
		(fp_line
			(start -0.7874 0.4064)
			(end -0.7874 -0.4064)
			(stroke
				(width 0.1524)
				(type default)
			)
			(layer "F.SilkS")
		)
		(fp_line
			(start 0.7874 -0.4064)
			(end 0.7874 0.4064)
			(stroke
				(width 0.1524)
				(type default)
			)
			(layer "F.SilkS")
		)
		(fp_line
			(start 0.7874 0.4064)
			(end -0.7874 0.4064)
			(stroke
				(width 0.1524)
				(type default)
			)
			(layer "F.SilkS")
		)
		(fp_line
			(start -0.67945 -0.305054)
			(end -0.12065 -0.305054)
			(stroke
				(width 0.1)
				(type default)
			)
			(layer "F.Fab")
		)
		(fp_line
			(start -0.67945 0.3048)
			(end -0.67945 -0.305054)
			(stroke
				(width 0.1)
				(type default)
			)
			(layer "F.Fab")
		)
		(fp_line
			(start -0.12065 -0.305054)
			(end -0.12065 -0.2794)
			(stroke
				(width 0.1)
				(type default)
			)
			(layer "F.Fab")
		)
		(fp_line
			(start -0.12065 -0.2794)
			(end 0.12065 -0.2794)
			(stroke
				(width 0.1)
				(type default)
			)
			(layer "F.Fab")
		)
		(fp_line
			(start -0.12065 0.2794)
			(end -0.12065 0.3048)
			(stroke
				(width 0.1)
				(type default)
			)
			(layer "F.Fab")
		)
		(fp_line
			(start -0.12065 0.3048)
			(end -0.67945 0.3048)
			(stroke
				(width 0.1)
				(type default)
			)
			(layer "F.Fab")
		)
		(fp_line
			(start 0.120396 0.2794)
			(end -0.12065 0.2794)
			(stroke
				(width 0.1)
				(type default)
			)
			(layer "F.Fab")
		)
		(fp_line
			(start 0.120396 0.3048)
			(end 0.120396 0.2794)
			(stroke
				(width 0.1)
				(type default)
			)
			(layer "F.Fab")
		)
		(fp_line
			(start 0.12065 -0.3048)
			(end 0.67945 -0.3048)
			(stroke
				(width 0.1)
				(type default)
			)
			(layer "F.Fab")
		)
		(fp_line
			(start 0.12065 -0.2794)
			(end 0.12065 -0.3048)
			(stroke
				(width 0.1)
				(type default)
			)
			(layer "F.Fab")
		)
		(fp_line
			(start 0.67945 -0.3048)
			(end 0.67945 0.3048)
			(stroke
				(width 0.1)
				(type default)
			)
			(layer "F.Fab")
		)
		(fp_line
			(start 0.67945 0.3048)
			(end 0.120396 0.3048)
			(stroke
				(width 0.1)
				(type default)
			)
			(layer "F.Fab")
		)
		(pad "1" smd circle
			(at -0.40005 0)
			(size 0 0)
			(layers "F.Cu" "F.Mask" "F.Paste")
			(net "PWRGD_P3V3_AUX_PDB_BUF_R")
		)
		(pad "2" smd circle
			(at 0.40005 0)
			(size 0 0)
			(layers "F.Cu" "F.Mask" "F.Paste")
			(net "PWRGD_P3V3_AUX_PDB_BUF")
		)
	)
	(footprint ""
		(layer "F.Cu")
		(at 114.826034 -66.672206 90)
		(property "Reference" "R806"
			(at 0 0 90)
			(layer "F.SilkS")
			(hide yes)
			(effects
				(font
					(size 1.27 1.27)
				)
			)
		)
		(property "Value" ""
			(at 0 0 90)
			(layer "F.Fab")
			(effects
				(font
					(size 1.27 1.27)
				)
			)
		)
		(duplicate_pad_numbers_are_jumpers no)
		(fp_line
			(start 0.7874 -0.4064)
			(end 0.7874 0.4064)
			(stroke
				(width 0.1524)
				(type default)
			)
			(layer "F.SilkS")
		)
		(fp_line
			(start -0.7874 -0.4064)
			(end 0.7874 -0.4064)
			(stroke
				(width 0.1524)
				(type default)
			)
			(layer "F.SilkS")
		)
		(fp_line
			(start 0.7874 0.4064)
			(end -0.7874 0.4064)
			(stroke
				(width 0.1524)
				(type default)
			)
			(layer "F.SilkS")
		)
		(fp_line
			(start -0.7874 0.4064)
			(end -0.7874 -0.4064)
			(stroke
				(width 0.1524)
				(type default)
			)
			(layer "F.SilkS")
		)
		(fp_line
			(start -0.12065 -0.305054)
			(end -0.12065 -0.2794)
			(stroke
				(width 0.1)
				(type default)
			)
			(layer "F.Fab")
		)
		(fp_line
			(start -0.67945 -0.305054)
			(end -0.12065 -0.305054)
			(stroke
				(width 0.1)
				(type default)
			)
			(layer "F.Fab")
		)
		(fp_line
			(start 0.67945 -0.3048)
			(end 0.67945 0.3048)
			(stroke
				(width 0.1)
				(type default)
			)
			(layer "F.Fab")
		)
		(fp_line
			(start 0.12065 -0.3048)
			(end 0.67945 -0.3048)
			(stroke
				(width 0.1)
				(type default)
			)
			(layer "F.Fab")
		)
		(fp_line
			(start 0.12065 -0.2794)
			(end 0.12065 -0.3048)
			(stroke
				(width 0.1)
				(type default)
			)
			(layer "F.Fab")
		)
		(fp_line
			(start -0.12065 -0.2794)
			(end 0.12065 -0.2794)
			(stroke
				(width 0.1)
				(type default)
			)
			(layer "F.Fab")
		)
		(fp_line
			(start 0.120396 0.2794)
			(end -0.12065 0.2794)
			(stroke
				(width 0.1)
				(type default)
			)
			(layer "F.Fab")
		)
		(fp_line
			(start -0.12065 0.2794)
			(end -0.12065 0.3048)
			(stroke
				(width 0.1)
				(type default)
			)
			(layer "F.Fab")
		)
		(fp_line
			(start 0.67945 0.3048)
			(end 0.120396 0.3048)
			(stroke
				(width 0.1)
				(type default)
			)
			(layer "F.Fab")
		)
		(fp_line
			(start 0.120396 0.3048)
			(end 0.120396 0.2794)
			(stroke
				(width 0.1)
				(type default)
			)
			(layer "F.Fab")
		)
		(fp_line
			(start -0.12065 0.3048)
			(end -0.67945 0.3048)
			(stroke
				(width 0.1)
				(type default)
			)
			(layer "F.Fab")
		)
		(fp_line
			(start -0.67945 0.3048)
			(end -0.67945 -0.305054)
			(stroke
				(width 0.1)
				(type default)
			)
			(layer "F.Fab")
		)
		(pad "1" smd circle
			(at -0.40005 0 90)
			(size 0 0)
			(layers "F.Cu" "F.Mask" "F.Paste")
			(net "JTAG_PLD_TCK_R")
		)
		(pad "2" smd circle
			(at 0.40005 0 90)
			(size 0 0)
			(layers "F.Cu" "F.Mask" "F.Paste")
			(net "JTAG_BMC_PLD_TCK")
		)
	)
)
